# T6G (Grand Teton) — schematic netlist excerpt (pin names and nets, part order shuffled) for the footprints in the layout excerpt that follows; sources: Cadence DE-HDL packaged netlist, KiCad conversion of 04192023_DAF0TMB3IC0_F0TG_MB_C_brd_V02_OCP.brd

R4203  Q_RES  1K 1% CHIP  pkg 0402LF  page 235 : A = U272_2_ADD0 ; B = GND
R1202  Q_RES  0 5% CHIP  pkg 0402LF  page 81 : A = FM_FORCE_ALL_PWRON_R ; B = FM_FORCE_ALL_PWRON

(kicad_pcb
	(version 20260206)
	(generator "pcbnew")
	(generator_version "10.0")
	(general
		(thickness 1.6)
		(legacy_teardrops no)
	)
	(paper "A4")
	(title_block
		(title "04192023_DAF0TMB3IC0_F0TG_MB_C_brd_V02_OCP.brd")
		(comment 1 "Grand Teton / footprints 2515-2516 of 8354")
	)
	(layers
		(0 "F.Cu" signal "TOP")
		(4 "In1.Cu" signal "GND")
		(6 "In2.Cu" signal "IN1")
		(8 "In3.Cu" signal "GND1")
		(10 "In4.Cu" signal "IN2")
		(12 "In5.Cu" signal "GND2")
		(14 "In6.Cu" signal "IN3")
		(16 "In7.Cu" signal "GND3")
		(18 "In8.Cu" signal "VCC")
		(20 "In9.Cu" signal "VCC1")
		(22 "In10.Cu" signal "GND4")
		(24 "In11.Cu" signal "IN4")
		(26 "In12.Cu" signal "GND5")
		(28 "In13.Cu" signal "IN5")
		(30 "In14.Cu" signal "GND6")
		(32 "In15.Cu" signal "IN6")
		(34 "In16.Cu" signal "GND7")
		(2 "B.Cu" signal "BOTTOM")
		(9 "F.Adhes" user "F.Adhesive")
		(11 "B.Adhes" user "B.Adhesive")
		(13 "F.Paste" user "Package Geometry/Pastemask Top")
		(15 "B.Paste" user "Package Geometry/Pastemask Bottom")
		(5 "F.SilkS" user "Ref Des/Silkscreen Top")
		(7 "B.SilkS" user "Ref Des/Silkscreen Bottom")
		(1 "F.Mask" user "Board Geometry/Soldermask Top")
		(3 "B.Mask" user "Board Geometry/Soldermask Bottom")
		(17 "Dwgs.User" user "User.Drawings")
		(19 "Cmts.User" user "User.Comments")
		(21 "Eco1.User" user "User.Eco1")
		(23 "Eco2.User" user "User.Eco2")
		(25 "Edge.Cuts" user "Board Geometry/Outline")
		(27 "Margin" user)
		(31 "F.CrtYd" user "Package Geometry/Place Bound Top")
		(29 "B.CrtYd" user "Package Geometry/Place Bound Bottom")
		(35 "F.Fab" user "Ref Des/Assembly Top")
		(33 "B.Fab" user "Ref Des/Assembly Bottom")
	)
	(footprint ""
		(layer "F.Cu")
		(at 194.183 -129.377948 90)
		(property "Reference" "R1202"
			(at 0 0 90)
			(layer "F.SilkS")
			(hide yes)
			(effects
				(font
					(size 1.27 1.27)
				)
			)
		)
		(property "Value" ""
			(at 0 0 90)
			(layer "F.Fab")
			(effects
				(font
					(size 1.27 1.27)
				)
			)
		)
		(duplicate_pad_numbers_are_jumpers no)
		(fp_line
			(start 0.7874 -0.4064)
			(end 0.7874 0.4064)
			(stroke
				(width 0.1524)
				(type default)
			)
			(layer "F.SilkS")
		)
		(fp_line
			(start -0.7874 -0.4064)
			(end 0.7874 -0.4064)
			(stroke
				(width 0.1524)
				(type default)
			)
			(layer "F.SilkS")
		)
		(fp_line
			(start 0.7874 0.4064)
			(end -0.7874 0.4064)
			(stroke
				(width 0.1524)
				(type default)
			)
			(layer "F.SilkS")
		)
		(fp_line
			(start -0.7874 0.4064)
			(end -0.7874 -0.4064)
			(stroke
				(width 0.1524)
				(type default)
			)
			(layer "F.SilkS")
		)
		(fp_line
			(start -0.12065 -0.305054)
			(end -0.12065 -0.2794)
			(stroke
				(width 0.1)
				(type default)
			)
			(layer "F.Fab")
		)
		(fp_line
			(start -0.67945 -0.305054)
			(end -0.12065 -0.305054)
			(stroke
				(width 0.1)
				(type default)
			)
			(layer "F.Fab")
		)
		(fp_line
			(start 0.67945 -0.3048)
			(end 0.67945 0.3048)
			(stroke
				(width 0.1)
				(type default)
			)
			(layer "F.Fab")
		)
		(fp_line
			(start 0.12065 -0.3048)
			(end 0.67945 -0.3048)
			(stroke
				(width 0.1)
				(type default)
			)
			(layer "F.Fab")
		)
		(fp_line
			(start 0.12065 -0.2794)
			(end 0.12065 -0.3048)
			(stroke
				(width 0.1)
				(type default)
			)
			(layer "F.Fab")
		)
		(fp_line
			(start -0.12065 -0.2794)
			(end 0.12065 -0.2794)
			(stroke
				(width 0.1)
				(type default)
			)
			(layer "F.Fab")
		)
		(fp_line
			(start 0.120396 0.2794)
			(end -0.12065 0.2794)
			(stroke
				(width 0.1)
				(type default)
			)
			(layer "F.Fab")
		)
		(fp_line
			(start -0.12065 0.2794)
			(end -0.12065 0.3048)
			(stroke
				(width 0.1)
				(type default)
			)
			(layer "F.Fab")
		)
		(fp_line
			(start 0.67945 0.3048)
			(end 0.120396 0.3048)
			(stroke
				(width 0.1)
				(type default)
			)
			(layer "F.Fab")
		)
		(fp_line
			(start 0.120396 0.3048)
			(end 0.120396 0.2794)
			(stroke
				(width 0.1)
				(type default)
			)
			(layer "F.Fab")
		)
		(fp_line
			(start -0.12065 0.3048)
			(end -0.67945 0.3048)
			(stroke
				(width 0.1)
				(type default)
			)
			(layer "F.Fab")
		)
		(fp_line
			(start -0.67945 0.3048)
			(end -0.67945 -0.305054)
			(stroke
				(width 0.1)
				(type default)
			)
			(layer "F.Fab")
		)
		(pad "1" smd circle
			(at -0.40005 0 90)
			(size 0 0)
			(layers "F.Cu" "F.Mask" "F.Paste")
			(net "FM_FORCE_ALL_PWRON_R")
		)
		(pad "2" smd circle
			(at 0.40005 0 90)
			(size 0 0)
			(layers "F.Cu" "F.Mask" "F.Paste")
			(net "FM_FORCE_ALL_PWRON")
		)
	)
	(footprint ""
		(layer "F.Cu")
		(at 99.015296 -422.43248 90)
		(property "Reference" "R4203"
			(at 0 0 90)
			(layer "F.SilkS")
			(hide yes)
			(effects
				(font
					(size 1.27 1.27)
				)
			)
		)
		(property "Value" ""
			(at 0 0 90)
			(layer "F.Fab")
			(effects
				(font
					(size 1.27 1.27)
				)
			)
		)
		(duplicate_pad_numbers_are_jumpers no)
		(fp_line
			(start 0.7874 -0.4064)
			(end 0.7874 0.4064)
			(stroke
				(width 0.1524)
				(type default)
			)
			(layer "F.SilkS")
		)
		(fp_line
			(start -0.7874 -0.4064)
			(end 0.7874 -0.4064)
			(stroke
				(width 0.1524)
				(type default)
			)
			(layer "F.SilkS")
		)
		(fp_line
			(start 0.7874 0.4064)
			(end -0.7874 0.4064)
			(stroke
				(width 0.1524)
				(type default)
			)
			(layer "F.SilkS")
		)
		(fp_line
			(start -0.7874 0.4064)
			(end -0.7874 -0.4064)
			(stroke
				(width 0.1524)
				(type default)
			)
			(layer "F.SilkS")
		)
		(fp_line
			(start -0.12065 -0.305054)
			(end -0.12065 -0.2794)
			(stroke
				(width 0.1)
				(type default)
			)
			(layer "F.Fab")
		)
		(fp_line
			(start -0.67945 -0.305054)
			(end -0.12065 -0.305054)
			(stroke
				(width 0.1)
				(type default)
			)
			(layer "F.Fab")
		)
		(fp_line
			(start 0.67945 -0.3048)
			(end 0.67945 0.3048)
			(stroke
				(width 0.1)
				(type default)
			)
			(layer "F.Fab")
		)
		(fp_line
			(start 0.12065 -0.3048)
			(end 0.67945 -0.3048)
			(stroke
				(width 0.1)
				(type default)
			)
			(layer "F.Fab")
		)
		(fp_line
			(start 0.12065 -0.2794)
			(end 0.12065 -0.3048)
			(stroke
				(width 0.1)
				(type default)
			)
			(layer "F.Fab")
		)
		(fp_line
			(start -0.12065 -0.2794)
			(end 0.12065 -0.2794)
			(stroke
				(width 0.1)
				(type default)
			)
			(layer "F.Fab")
		)
		(fp_line
			(start 0.120396 0.2794)
			(end -0.12065 0.2794)
			(stroke
				(width 0.1)
				(type default)
			)
			(layer "F.Fab")
		)
		(fp_line
			(start -0.12065 0.2794)
			(end -0.12065 0.3048)
			(stroke
				(width 0.1)
				(type default)
			)
			(layer "F.Fab")
		)
		(fp_line
			(start 0.67945 0.3048)
			(end 0.120396 0.3048)
			(stroke
				(width 0.1)
				(type default)
			)
			(layer "F.Fab")
		)
		(fp_line
			(start 0.120396 0.3048)
			(end 0.120396 0.2794)
			(stroke
				(width 0.1)
				(type default)
			)
			(layer "F.Fab")
		)
		(fp_line
			(start -0.12065 0.3048)
			(end -0.67945 0.3048)
			(stroke
				(width 0.1)
				(type default)
			)
			(layer "F.Fab")
		)
		(fp_line
			(start -0.67945 0.3048)
			(end -0.67945 -0.305054)
			(stroke
				(width 0.1)
				(type default)
			)
			(layer "F.Fab")
		)
		(pad "1" smd circle
			(at -0.40005 0 90)
			(size 0 0)
			(layers "F.Cu" "F.Mask" "F.Paste")
			(net "U272_2_ADD0")
		)
		(pad "2" smd circle
			(at 0.40005 0 90)
			(size 0 0)
			(layers "F.Cu" "F.Mask" "F.Paste")
			(net "GND")
		)
	)
)
